(kicad_pcb
	(version 20260206)
	(generator "pcbnew")
	(generator_version "10.0")
	(general
		(thickness 1.6)
		(legacy_teardrops no)
	)
	(paper "A4")
	(title_block
		(title "03242023_DA0F0TMBIJ0_F0T_Motherboard_J_brd_V01_OCP.brd")
		(comment 1 "Grand Teton / footprint 3586 of 6105 (J23), pads 1-112 of 291")
	)
	(layers
		(0 "F.Cu" signal "TOP")
		(4 "In1.Cu" signal "GND")
		(6 "In2.Cu" signal "IN1")
		(8 "In3.Cu" signal "GND1")
		(10 "In4.Cu" signal "IN2")
		(12 "In5.Cu" signal "GND2")
		(14 "In6.Cu" signal "IN3")
		(16 "In7.Cu" signal "GND3")
		(18 "In8.Cu" signal "VCC")
		(20 "In9.Cu" signal "VCC1")
		(22 "In10.Cu" signal "GND4")
		(24 "In11.Cu" signal "IN4")
		(26 "In12.Cu" signal "GND5")
		(28 "In13.Cu" signal "IN5")
		(30 "In14.Cu" signal "GND6")
		(32 "In15.Cu" signal "IN6")
		(34 "In16.Cu" signal "GND7")
		(2 "B.Cu" signal "BOTTOM")
		(9 "F.Adhes" user "F.Adhesive")
		(11 "B.Adhes" user "B.Adhesive")
		(13 "F.Paste" user "Package Geometry/Pastemask Top")
		(15 "B.Paste" user "Package Geometry/Pastemask Bottom")
		(5 "F.SilkS" user "Ref Des/Silkscreen Top")
		(7 "B.SilkS" user "Ref Des/Silkscreen Bottom")
		(1 "F.Mask" user "Board Geometry/Soldermask Top")
		(3 "B.Mask" user "Board Geometry/Soldermask Bottom")
		(17 "Dwgs.User" user "User.Drawings")
		(19 "Cmts.User" user "User.Comments")
		(21 "Eco1.User" user "User.Eco1")
		(23 "Eco2.User" user "User.Eco2")
		(25 "Edge.Cuts" user "Board Geometry/Outline")
		(27 "Margin" user)
		(31 "F.CrtYd" user "Package Geometry/Place Bound Top")
		(29 "B.CrtYd" user "Package Geometry/Place Bound Bottom")
		(35 "F.Fab" user "Ref Des/Assembly Top")
		(33 "B.Fab" user "Ref Des/Assembly Bottom")
	)
	(footprint ""
		(layer "F.Cu")
		(at 10.19048 -258.091686)
		(property "Reference" "J23"
			(at -5.69468 -80.480408 0)
			(unlocked yes)
			(layer "F.SilkS")
			(effects
				(font
					(size 0.7874 0.5842)
					(thickness 0.1524)
				)
				(justify left)
			)
		)
		(property "Value" ""
			(at 0 0 0)
			(layer "F.Fab")
			(effects
				(font
					(size 1.27 1.27)
				)
			)
		)
		(duplicate_pad_numbers_are_jumpers no)
		(pad "1" smd rect
			(at -2.050034 -63.324994 270)
			(size 0.519938 1.4986)
			(layers "F.Cu" "F.Mask" "F.Paste")
			(net "P12V_S3_AUX_CPU1_NVDIMM")
		)
		(pad "2" smd rect
			(at -2.050034 -62.47511 270)
			(size 0.519938 1.4986)
			(layers "F.Cu" "F.Mask" "F.Paste")
			(net "TP_CHD_CPU1_DIMM1_FRU_0")
		)
		(pad "3" smd rect
			(at -2.050034 -61.624972 270)
			(size 0.519938 1.4986)
			(layers "F.Cu" "F.Mask" "F.Paste")
			(net "P3V3_AUX")
		)
		(pad "4" smd rect
			(at -2.050034 -60.775088 270)
			(size 0.519938 1.4986)
			(layers "F.Cu" "F.Mask" "F.Paste")
			(net "I3C_SPD_DDRABCD_CPU1_LVC1_SCL_6")
		)
		(pad "5" smd rect
			(at -2.050034 -59.92495 270)
			(size 0.519938 1.4986)
			(layers "F.Cu" "F.Mask" "F.Paste")
			(net "I3C_SPD_DDRABCD_CPU1_LVC1_SDA")
		)
		(pad "6" smd rect
			(at -2.050034 -59.075066 270)
			(size 0.519938 1.4986)
			(layers "F.Cu" "F.Mask" "F.Paste")
			(net "GND")
		)
		(pad "7" smd rect
			(at -2.050034 -58.224928 270)
			(size 0.519938 1.4986)
			(layers "F.Cu" "F.Mask" "F.Paste")
			(net "M_D_CPU1_SA_DQ<0>")
		)
		(pad "8" smd rect
			(at -2.050034 -57.375044 270)
			(size 0.519938 1.4986)
			(layers "F.Cu" "F.Mask" "F.Paste")
			(net "GND")
		)
		(pad "9" smd rect
			(at -2.050034 -56.524906 270)
			(size 0.519938 1.4986)
			(layers "F.Cu" "F.Mask" "F.Paste")
			(net "M_D_CPU1_SA_DQ<1>")
		)
		(pad "10" smd rect
			(at -2.050034 -55.675022 270)
			(size 0.519938 1.4986)
			(layers "F.Cu" "F.Mask" "F.Paste")
			(net "GND")
		)
		(pad "11" smd rect
			(at -2.050034 -54.824884 270)
			(size 0.519938 1.4986)
			(layers "F.Cu" "F.Mask" "F.Paste")
			(net "M_D_CPU1_SA_DQS_DP<0>")
		)
		(pad "12" smd rect
			(at -2.050034 -53.975 270)
			(size 0.519938 1.4986)
			(layers "F.Cu" "F.Mask" "F.Paste")
			(net "M_D_CPU1_SA_DQS_DN<0>")
		)
		(pad "13" smd rect
			(at -2.050034 -53.125116 270)
			(size 0.519938 1.4986)
			(layers "F.Cu" "F.Mask" "F.Paste")
			(net "GND")
		)
		(pad "14" smd rect
			(at -2.050034 -52.274978 270)
			(size 0.519938 1.4986)
			(layers "F.Cu" "F.Mask" "F.Paste")
			(net "M_D_CPU1_SA_DQ<4>")
		)
		(pad "15" smd rect
			(at -2.050034 -51.425094 270)
			(size 0.519938 1.4986)
			(layers "F.Cu" "F.Mask" "F.Paste")
			(net "GND")
		)
		(pad "16" smd rect
			(at -2.050034 -50.574956 270)
			(size 0.519938 1.4986)
			(layers "F.Cu" "F.Mask" "F.Paste")
			(net "M_D_CPU1_SA_DQ<5>")
		)
		(pad "17" smd rect
			(at -2.050034 -49.725072 270)
			(size 0.519938 1.4986)
			(layers "F.Cu" "F.Mask" "F.Paste")
			(net "GND")
		)
		(pad "18" smd rect
			(at -2.050034 -48.874934 270)
			(size 0.519938 1.4986)
			(layers "F.Cu" "F.Mask" "F.Paste")
			(net "M_D_CPU1_SA_DQ<8>")
		)
		(pad "19" smd rect
			(at -2.050034 -48.02505 270)
			(size 0.519938 1.4986)
			(layers "F.Cu" "F.Mask" "F.Paste")
			(net "GND")
		)
		(pad "20" smd rect
			(at -2.050034 -47.174912 270)
			(size 0.519938 1.4986)
			(layers "F.Cu" "F.Mask" "F.Paste")
			(net "M_D_CPU1_SA_DQ<9>")
		)
		(pad "21" smd rect
			(at -2.050034 -46.325028 270)
			(size 0.519938 1.4986)
			(layers "F.Cu" "F.Mask" "F.Paste")
			(net "GND")
		)
		(pad "22" smd rect
			(at -2.050034 -45.47489 270)
			(size 0.519938 1.4986)
			(layers "F.Cu" "F.Mask" "F.Paste")
			(net "M_D_CPU1_SA_DQS_DP<1>")
		)
		(pad "23" smd rect
			(at -2.050034 -44.625006 270)
			(size 0.519938 1.4986)
			(layers "F.Cu" "F.Mask" "F.Paste")
			(net "M_D_CPU1_SA_DQS_DN<1>")
		)
		(pad "24" smd rect
			(at -2.050034 -43.775122 270)
			(size 0.519938 1.4986)
			(layers "F.Cu" "F.Mask" "F.Paste")
			(net "GND")
		)
		(pad "25" smd rect
			(at -2.050034 -42.924984 270)
			(size 0.519938 1.4986)
			(layers "F.Cu" "F.Mask" "F.Paste")
			(net "M_D_CPU1_SA_DQ<12>")
		)
		(pad "26" smd rect
			(at -2.050034 -42.0751 270)
			(size 0.519938 1.4986)
			(layers "F.Cu" "F.Mask" "F.Paste")
			(net "GND")
		)
		(pad "27" smd rect
			(at -2.050034 -41.224962 270)
			(size 0.519938 1.4986)
			(layers "F.Cu" "F.Mask" "F.Paste")
			(net "M_D_CPU1_SA_DQ<13>")
		)
		(pad "28" smd rect
			(at -2.050034 -40.375078 270)
			(size 0.519938 1.4986)
			(layers "F.Cu" "F.Mask" "F.Paste")
			(net "GND")
		)
		(pad "29" smd rect
			(at -2.050034 -39.52494 270)
			(size 0.519938 1.4986)
			(layers "F.Cu" "F.Mask" "F.Paste")
			(net "M_D_CPU1_SA_DQ<16>")
		)
		(pad "30" smd rect
			(at -2.050034 -38.675056 270)
			(size 0.519938 1.4986)
			(layers "F.Cu" "F.Mask" "F.Paste")
			(net "GND")
		)
		(pad "31" smd rect
			(at -2.050034 -37.824918 270)
			(size 0.519938 1.4986)
			(layers "F.Cu" "F.Mask" "F.Paste")
			(net "M_D_CPU1_SA_DQ<17>")
		)
		(pad "32" smd rect
			(at -2.050034 -36.975034 270)
			(size 0.519938 1.4986)
			(layers "F.Cu" "F.Mask" "F.Paste")
			(net "GND")
		)
		(pad "33" smd rect
			(at -2.050034 -36.124896 270)
			(size 0.519938 1.4986)
			(layers "F.Cu" "F.Mask" "F.Paste")
			(net "M_D_CPU1_SA_DQS_DP<2>")
		)
		(pad "34" smd rect
			(at -2.050034 -35.275012 270)
			(size 0.519938 1.4986)
			(layers "F.Cu" "F.Mask" "F.Paste")
			(net "M_D_CPU1_SA_DQS_DN<2>")
		)
		(pad "35" smd rect
			(at -2.050034 -34.425128 270)
			(size 0.519938 1.4986)
			(layers "F.Cu" "F.Mask" "F.Paste")
			(net "GND")
		)
		(pad "36" smd rect
			(at -2.050034 -33.57499 270)
			(size 0.519938 1.4986)
			(layers "F.Cu" "F.Mask" "F.Paste")
			(net "M_D_CPU1_SA_DQ<20>")
		)
		(pad "37" smd rect
			(at -2.050034 -32.725106 270)
			(size 0.519938 1.4986)
			(layers "F.Cu" "F.Mask" "F.Paste")
			(net "GND")
		)
		(pad "38" smd rect
			(at -2.050034 -31.874968 270)
			(size 0.519938 1.4986)
			(layers "F.Cu" "F.Mask" "F.Paste")
			(net "M_D_CPU1_SA_DQ<21>")
		)
		(pad "39" smd rect
			(at -2.050034 -31.025084 270)
			(size 0.519938 1.4986)
			(layers "F.Cu" "F.Mask" "F.Paste")
			(net "GND")
		)
		(pad "40" smd rect
			(at -2.050034 -30.174946 270)
			(size 0.519938 1.4986)
			(layers "F.Cu" "F.Mask" "F.Paste")
			(net "M_D_CPU1_SA_DQ<24>")
		)
		(pad "41" smd rect
			(at -2.050034 -29.325062 270)
			(size 0.519938 1.4986)
			(layers "F.Cu" "F.Mask" "F.Paste")
			(net "GND")
		)
		(pad "42" smd rect
			(at -2.050034 -28.474924 270)
			(size 0.519938 1.4986)
			(layers "F.Cu" "F.Mask" "F.Paste")
			(net "M_D_CPU1_SA_DQ<25>")
		)
		(pad "43" smd rect
			(at -2.050034 -27.62504 270)
			(size 0.519938 1.4986)
			(layers "F.Cu" "F.Mask" "F.Paste")
			(net "GND")
		)
		(pad "44" smd rect
			(at -2.050034 -26.774902 270)
			(size 0.519938 1.4986)
			(layers "F.Cu" "F.Mask" "F.Paste")
			(net "M_D_CPU1_SA_DQS_DP<3>")
		)
		(pad "45" smd rect
			(at -2.050034 -25.925018 270)
			(size 0.519938 1.4986)
			(layers "F.Cu" "F.Mask" "F.Paste")
			(net "M_D_CPU1_SA_DQS_DN<3>")
		)
		(pad "46" smd rect
			(at -2.050034 -25.07488 270)
			(size 0.519938 1.4986)
			(layers "F.Cu" "F.Mask" "F.Paste")
			(net "GND")
		)
		(pad "47" smd rect
			(at -2.050034 -24.224996 270)
			(size 0.519938 1.4986)
			(layers "F.Cu" "F.Mask" "F.Paste")
			(net "M_D_CPU1_SA_DQ<28>")
		)
		(pad "48" smd rect
			(at -2.050034 -23.375112 270)
			(size 0.519938 1.4986)
			(layers "F.Cu" "F.Mask" "F.Paste")
			(net "GND")
		)
		(pad "49" smd rect
			(at -2.050034 -22.524974 270)
			(size 0.519938 1.4986)
			(layers "F.Cu" "F.Mask" "F.Paste")
			(net "M_D_CPU1_SA_DQ<29>")
		)
		(pad "50" smd rect
			(at -2.050034 -21.67509 270)
			(size 0.519938 1.4986)
			(layers "F.Cu" "F.Mask" "F.Paste")
			(net "GND")
		)
		(pad "51" smd rect
			(at -2.050034 -20.824952 270)
			(size 0.519938 1.4986)
			(layers "F.Cu" "F.Mask" "F.Paste")
			(net "M_D_CPU1_SA_CB<0>")
		)
		(pad "52" smd rect
			(at -2.050034 -19.975068 270)
			(size 0.519938 1.4986)
			(layers "F.Cu" "F.Mask" "F.Paste")
			(net "GND")
		)
		(pad "53" smd rect
			(at -2.050034 -19.12493 270)
			(size 0.519938 1.4986)
			(layers "F.Cu" "F.Mask" "F.Paste")
			(net "M_D_CPU1_SA_CB<1>")
		)
		(pad "54" smd rect
			(at -2.050034 -18.275046 270)
			(size 0.519938 1.4986)
			(layers "F.Cu" "F.Mask" "F.Paste")
			(net "GND")
		)
		(pad "55" smd rect
			(at -2.050034 -17.424908 270)
			(size 0.519938 1.4986)
			(layers "F.Cu" "F.Mask" "F.Paste")
			(net "M_D_CPU1_SA_DQS_DP<4>")
		)
		(pad "56" smd rect
			(at -2.050034 -16.575024 270)
			(size 0.519938 1.4986)
			(layers "F.Cu" "F.Mask" "F.Paste")
			(net "M_D_CPU1_SA_DQS_DN<4>")
		)
		(pad "57" smd rect
			(at -2.050034 -15.724886 270)
			(size 0.519938 1.4986)
			(layers "F.Cu" "F.Mask" "F.Paste")
			(net "GND")
		)
		(pad "58" smd rect
			(at -2.050034 -14.875002 270)
			(size 0.519938 1.4986)
			(layers "F.Cu" "F.Mask" "F.Paste")
			(net "M_D_CPU1_SA_CB<4>")
		)
		(pad "59" smd rect
			(at -2.050034 -14.025118 270)
			(size 0.519938 1.4986)
			(layers "F.Cu" "F.Mask" "F.Paste")
			(net "GND")
		)
		(pad "60" smd rect
			(at -2.050034 -13.17498 270)
			(size 0.519938 1.4986)
			(layers "F.Cu" "F.Mask" "F.Paste")
			(net "M_D_CPU1_SA_CB<5>")
		)
		(pad "61" smd rect
			(at -2.050034 -12.325096 270)
			(size 0.519938 1.4986)
			(layers "F.Cu" "F.Mask" "F.Paste")
			(net "GND")
		)
		(pad "62" smd rect
			(at -2.050034 -11.474958 270)
			(size 0.519938 1.4986)
			(layers "F.Cu" "F.Mask" "F.Paste")
			(net "M_D_CPU1_ALERT_N")
		)
		(pad "63" smd rect
			(at -2.050034 -10.625074 270)
			(size 0.519938 1.4986)
			(layers "F.Cu" "F.Mask" "F.Paste")
			(net "GND")
		)
		(pad "64" smd rect
			(at -2.050034 -9.774936 270)
			(size 0.519938 1.4986)
			(layers "F.Cu" "F.Mask" "F.Paste")
			(net "M_D_CPU1_SA_CS_N<0>")
		)
		(pad "65" smd rect
			(at -2.050034 -8.925052 270)
			(size 0.519938 1.4986)
			(layers "F.Cu" "F.Mask" "F.Paste")
			(net "GND")
		)
		(pad "66" smd rect
			(at -2.050034 -8.074914 270)
			(size 0.519938 1.4986)
			(layers "F.Cu" "F.Mask" "F.Paste")
			(net "M_D_CPU1_SA_CA<0>")
		)
		(pad "67" smd rect
			(at -2.050034 -7.22503 270)
			(size 0.519938 1.4986)
			(layers "F.Cu" "F.Mask" "F.Paste")
			(net "GND")
		)
		(pad "68" smd rect
			(at -2.050034 -6.374892 270)
			(size 0.519938 1.4986)
			(layers "F.Cu" "F.Mask" "F.Paste")
			(net "M_D_CPU1_SA_CA<2>")
		)
		(pad "69" smd rect
			(at -2.050034 -5.525008 270)
			(size 0.519938 1.4986)
			(layers "F.Cu" "F.Mask" "F.Paste")
			(net "GND")
		)
		(pad "70" smd rect
			(at -2.050034 -4.675124 270)
			(size 0.519938 1.4986)
			(layers "F.Cu" "F.Mask" "F.Paste")
			(net "M_D_CPU1_SA_CA<4>")
		)
		(pad "71" smd rect
			(at -2.050034 -3.824986 270)
			(size 0.519938 1.4986)
			(layers "F.Cu" "F.Mask" "F.Paste")
			(net "GND")
		)
		(pad "72" smd rect
			(at -2.050034 -2.975102 270)
			(size 0.519938 1.4986)
			(layers "F.Cu" "F.Mask" "F.Paste")
			(net "M_D_CPU1_SA_CA<6>")
		)
		(pad "73" smd rect
			(at -2.050034 -2.124964 270)
			(size 0.519938 1.4986)
			(layers "F.Cu" "F.Mask" "F.Paste")
			(net "GND")
		)
		(pad "74" smd rect
			(at -2.050034 -1.27508 270)
			(size 0.519938 1.4986)
			(layers "F.Cu" "F.Mask" "F.Paste")
			(net "M_D_CPU1_SA_PAR")
		)
		(pad "75" smd rect
			(at -2.050034 -0.424942 270)
			(size 0.519938 1.4986)
			(layers "F.Cu" "F.Mask" "F.Paste")
			(net "GND")
		)
		(pad "76" smd rect
			(at -2.050034 5.525008 270)
			(size 0.519938 1.4986)
			(layers "F.Cu" "F.Mask" "F.Paste")
			(net "M_D_CPU1_SB_CA<0>")
		)
		(pad "77" smd rect
			(at -2.050034 6.374892 270)
			(size 0.519938 1.4986)
			(layers "F.Cu" "F.Mask" "F.Paste")
			(net "GND")
		)
		(pad "78" smd rect
			(at -2.050034 7.22503 270)
			(size 0.519938 1.4986)
			(layers "F.Cu" "F.Mask" "F.Paste")
			(net "M_D_CPU1_SB_CA<2>")
		)
		(pad "79" smd rect
			(at -2.050034 8.074914 270)
			(size 0.519938 1.4986)
			(layers "F.Cu" "F.Mask" "F.Paste")
			(net "GND")
		)
		(pad "80" smd rect
			(at -2.050034 8.925052 270)
			(size 0.519938 1.4986)
			(layers "F.Cu" "F.Mask" "F.Paste")
			(net "M_D_CPU1_SB_CA<4>")
		)
		(pad "81" smd rect
			(at -2.050034 9.774936 270)
			(size 0.519938 1.4986)
			(layers "F.Cu" "F.Mask" "F.Paste")
			(net "GND")
		)
		(pad "82" smd rect
			(at -2.050034 10.625074 270)
			(size 0.519938 1.4986)
			(layers "F.Cu" "F.Mask" "F.Paste")
			(net "M_D_CPU1_SB_CA<6>")
		)
		(pad "83" smd rect
			(at -2.050034 11.474958 270)
			(size 0.519938 1.4986)
			(layers "F.Cu" "F.Mask" "F.Paste")
			(net "GND")
		)
		(pad "84" smd rect
			(at -2.050034 12.325096 270)
			(size 0.519938 1.4986)
			(layers "F.Cu" "F.Mask" "F.Paste")
			(net "M_D_CPU1_SB_CS_N<0>")
		)
		(pad "85" smd rect
			(at -2.050034 13.17498 270)
			(size 0.519938 1.4986)
			(layers "F.Cu" "F.Mask" "F.Paste")
			(net "GND")
		)
		(pad "86" smd rect
			(at -2.050034 14.025118 270)
			(size 0.519938 1.4986)
			(layers "F.Cu" "F.Mask" "F.Paste")
			(net "M_D_CPU1_SA_RSP<0>")
		)
		(pad "87" smd rect
			(at -2.050034 14.875002 270)
			(size 0.519938 1.4986)
			(layers "F.Cu" "F.Mask" "F.Paste")
			(net "M_D_CPU1_SB_RSP<0>")
		)
		(pad "88" smd rect
			(at -2.050034 15.724886 270)
			(size 0.519938 1.4986)
			(layers "F.Cu" "F.Mask" "F.Paste")
			(net "GND")
		)
		(pad "89" smd rect
			(at -2.050034 16.575024 270)
			(size 0.519938 1.4986)
			(layers "F.Cu" "F.Mask" "F.Paste")
			(net "M_D_CPU1_SB_CB<4>")
		)
		(pad "90" smd rect
			(at -2.050034 17.424908 270)
			(size 0.519938 1.4986)
			(layers "F.Cu" "F.Mask" "F.Paste")
			(net "GND")
		)
		(pad "91" smd rect
			(at -2.050034 18.275046 270)
			(size 0.519938 1.4986)
			(layers "F.Cu" "F.Mask" "F.Paste")
			(net "M_D_CPU1_SB_CB<5>")
		)
		(pad "92" smd rect
			(at -2.050034 19.12493 270)
			(size 0.519938 1.4986)
			(layers "F.Cu" "F.Mask" "F.Paste")
			(net "GND")
		)
		(pad "93" smd rect
			(at -2.050034 19.975068 270)
			(size 0.519938 1.4986)
			(layers "F.Cu" "F.Mask" "F.Paste")
			(net "M_D_CPU1_SB_DQS_DP<9>")
		)
		(pad "94" smd rect
			(at -2.050034 20.824952 270)
			(size 0.519938 1.4986)
			(layers "F.Cu" "F.Mask" "F.Paste")
			(net "M_D_CPU1_SB_DQS_DN<9>")
		)
		(pad "95" smd rect
			(at -2.050034 21.67509 270)
			(size 0.519938 1.4986)
			(layers "F.Cu" "F.Mask" "F.Paste")
			(net "GND")
		)
		(pad "96" smd rect
			(at -2.050034 22.524974 270)
			(size 0.519938 1.4986)
			(layers "F.Cu" "F.Mask" "F.Paste")
			(net "M_D_CPU1_SB_CB<0>")
		)
		(pad "97" smd rect
			(at -2.050034 23.375112 270)
			(size 0.519938 1.4986)
			(layers "F.Cu" "F.Mask" "F.Paste")
			(net "GND")
		)
		(pad "98" smd rect
			(at -2.050034 24.224996 270)
			(size 0.519938 1.4986)
			(layers "F.Cu" "F.Mask" "F.Paste")
			(net "M_D_CPU1_SB_CB<1>")
		)
		(pad "99" smd rect
			(at -2.050034 25.07488 270)
			(size 0.519938 1.4986)
			(layers "F.Cu" "F.Mask" "F.Paste")
			(net "GND")
		)
		(pad "100" smd rect
			(at -2.050034 25.925018 270)
			(size 0.519938 1.4986)
			(layers "F.Cu" "F.Mask" "F.Paste")
			(net "M_D_CPU1_SB_DQ<0>")
		)
		(pad "101" smd rect
			(at -2.050034 26.774902 270)
			(size 0.519938 1.4986)
			(layers "F.Cu" "F.Mask" "F.Paste")
			(net "GND")
		)
		(pad "102" smd rect
			(at -2.050034 27.62504 270)
			(size 0.519938 1.4986)
			(layers "F.Cu" "F.Mask" "F.Paste")
			(net "M_D_CPU1_SB_DQ<1>")
		)
		(pad "103" smd rect
			(at -2.050034 28.474924 270)
			(size 0.519938 1.4986)
			(layers "F.Cu" "F.Mask" "F.Paste")
			(net "GND")
		)
		(pad "104" smd rect
			(at -2.050034 29.325062 270)
			(size 0.519938 1.4986)
			(layers "F.Cu" "F.Mask" "F.Paste")
			(net "M_D_CPU1_SB_DQS_DP<0>")
		)
		(pad "105" smd rect
			(at -2.050034 30.174946 270)
			(size 0.519938 1.4986)
			(layers "F.Cu" "F.Mask" "F.Paste")
			(net "M_D_CPU1_SB_DQS_DN<0>")
		)
		(pad "106" smd rect
			(at -2.050034 31.025084 270)
			(size 0.519938 1.4986)
			(layers "F.Cu" "F.Mask" "F.Paste")
			(net "GND")
		)
		(pad "107" smd rect
			(at -2.050034 31.874968 270)
			(size 0.519938 1.4986)
			(layers "F.Cu" "F.Mask" "F.Paste")
			(net "M_D_CPU1_SB_DQ<4>")
		)
		(pad "108" smd rect
			(at -2.050034 32.725106 270)
			(size 0.519938 1.4986)
			(layers "F.Cu" "F.Mask" "F.Paste")
			(net "GND")
		)
		(pad "109" smd rect
			(at -2.050034 33.57499 270)
			(size 0.519938 1.4986)
			(layers "F.Cu" "F.Mask" "F.Paste")
			(net "M_D_CPU1_SB_DQ<5>")
		)
		(pad "110" smd rect
			(at -2.050034 34.425128 270)
			(size 0.519938 1.4986)
			(layers "F.Cu" "F.Mask" "F.Paste")
			(net "GND")
		)
		(pad "111" smd rect
			(at -2.050034 35.275012 270)
			(size 0.519938 1.4986)
			(layers "F.Cu" "F.Mask" "F.Paste")
			(net "M_D_CPU1_SB_DQ<8>")
		)
		(pad "112" smd rect
			(at -2.050034 36.124896 270)
			(size 0.519938 1.4986)
			(layers "F.Cu" "F.Mask" "F.Paste")
			(net "GND")
		)
	)
)
